(kicad_pcb
	(version 20260206)
	(generator "pcbnew")
	(generator_version "10.0")
	(general
		(thickness 1.6)
		(legacy_teardrops no)
	)
	(paper "A4")
	(title_block
		(title "Wiwynn_Tioga_Pass_MB.brd")
		(comment 1 "Tioga Pass / footprint 4084 of 4770 (J9T1), pads 244-291 of 291")
	)
	(layers
		(0 "F.Cu" signal "TOP")
		(4 "In1.Cu" signal "L2GND")
		(6 "In2.Cu" signal "L3")
		(8 "In3.Cu" signal "L4GND")
		(10 "In4.Cu" signal "L5")
		(12 "In5.Cu" signal "L6GND")
		(14 "In6.Cu" signal "L7VCC")
		(16 "In7.Cu" signal "L8VCC")
		(18 "In8.Cu" signal "L9GND")
		(20 "In9.Cu" signal "L10")
		(22 "In10.Cu" signal "L11GND")
		(24 "In11.Cu" signal "L12")
		(26 "In12.Cu" signal "L13GND")
		(2 "B.Cu" signal "BOTTOM")
		(9 "F.Adhes" user "F.Adhesive")
		(11 "B.Adhes" user "B.Adhesive")
		(13 "F.Paste" user "Package Geometry/Pastemask Top")
		(15 "B.Paste" user "Package Geometry/Pastemask Bottom")
		(5 "F.SilkS" user "Ref Des/Silkscreen Top")
		(7 "B.SilkS" user "Ref Des/Silkscreen Bottom")
		(1 "F.Mask" user "Board Geometry/Soldermask Top")
		(3 "B.Mask" user "Board Geometry/Soldermask Bottom")
		(17 "Dwgs.User" user "User.Drawings")
		(19 "Cmts.User" user "User.Comments")
		(21 "Eco1.User" user "User.Eco1")
		(23 "Eco2.User" user "User.Eco2")
		(25 "Edge.Cuts" user "Board Geometry/Outline")
		(27 "Margin" user)
		(31 "F.CrtYd" user "Package Geometry/Place Bound Top")
		(29 "B.CrtYd" user "Package Geometry/Place Bound Bottom")
		(35 "F.Fab" user "Ref Des/Assembly Top")
		(33 "B.Fab" user "Ref Des/Assembly Bottom")
	)
	(footprint ""
		(layer "B.Cu")
		(at 29.699458 -24.824182 90)
		(property "Reference" "J9T1"
			(at 2.200148 39.261542 0)
			(unlocked yes)
			(layer "B.SilkS")
			(effects
				(font
					(size 0.7874 0.5842)
					(thickness 0.1524)
				)
				(justify left mirror)
			)
		)
		(property "Value" ""
			(at 0 0 90)
			(layer "B.Fab")
			(effects
				(font
					(size 1.27 1.27)
				)
				(justify mirror)
			)
		)
		(duplicate_pad_numbers_are_jumpers no)
		(pad "241" smd rect
			(at -4.59994 86.700106 270)
			(size 1.8034 0.508)
			(layers "B.Cu" "B.Mask" "B.Paste")
			(net "GND")
		)
		(pad "242" smd rect
			(at -4.59994 87.54999 270)
			(size 1.8034 0.508)
			(layers "B.Cu" "B.Mask" "B.Paste")
			(net "M_G_DQ<33>")
		)
		(pad "243" smd rect
			(at -4.59994 88.399874 270)
			(size 1.8034 0.508)
			(layers "B.Cu" "B.Mask" "B.Paste")
			(net "GND")
		)
		(pad "244" smd rect
			(at -4.59994 89.250012 270)
			(size 1.8034 0.508)
			(layers "B.Cu" "B.Mask" "B.Paste")
			(net "M_G_DQS_DN<4>")
		)
		(pad "245" smd rect
			(at -4.59994 90.099896 270)
			(size 1.8034 0.508)
			(layers "B.Cu" "B.Mask" "B.Paste")
			(net "M_G_DQS_DP<4>")
		)
		(pad "246" smd rect
			(at -4.59994 90.950034 270)
			(size 1.8034 0.508)
			(layers "B.Cu" "B.Mask" "B.Paste")
			(net "GND")
		)
		(pad "247" smd rect
			(at -4.59994 91.799918 270)
			(size 1.8034 0.508)
			(layers "B.Cu" "B.Mask" "B.Paste")
			(net "M_G_DQ<39>")
		)
		(pad "248" smd rect
			(at -4.59994 92.650056 270)
			(size 1.8034 0.508)
			(layers "B.Cu" "B.Mask" "B.Paste")
			(net "GND")
		)
		(pad "249" smd rect
			(at -4.59994 93.49994 270)
			(size 1.8034 0.508)
			(layers "B.Cu" "B.Mask" "B.Paste")
			(net "M_G_DQ<35>")
		)
		(pad "250" smd rect
			(at -4.59994 94.350078 270)
			(size 1.8034 0.508)
			(layers "B.Cu" "B.Mask" "B.Paste")
			(net "GND")
		)
		(pad "251" smd rect
			(at -4.59994 95.199962 270)
			(size 1.8034 0.508)
			(layers "B.Cu" "B.Mask" "B.Paste")
			(net "M_G_DQ<45>")
		)
		(pad "252" smd rect
			(at -4.59994 96.0501 270)
			(size 1.8034 0.508)
			(layers "B.Cu" "B.Mask" "B.Paste")
			(net "GND")
		)
		(pad "253" smd rect
			(at -4.59994 96.899984 270)
			(size 1.8034 0.508)
			(layers "B.Cu" "B.Mask" "B.Paste")
			(net "M_G_DQ<41>")
		)
		(pad "254" smd rect
			(at -4.59994 97.750122 270)
			(size 1.8034 0.508)
			(layers "B.Cu" "B.Mask" "B.Paste")
			(net "GND")
		)
		(pad "255" smd rect
			(at -4.59994 98.600006 270)
			(size 1.8034 0.508)
			(layers "B.Cu" "B.Mask" "B.Paste")
			(net "M_G_DQS_DN<5>")
		)
		(pad "256" smd rect
			(at -4.59994 99.44989 270)
			(size 1.8034 0.508)
			(layers "B.Cu" "B.Mask" "B.Paste")
			(net "M_G_DQS_DP<5>")
		)
		(pad "257" smd rect
			(at -4.59994 100.300028 270)
			(size 1.8034 0.508)
			(layers "B.Cu" "B.Mask" "B.Paste")
			(net "GND")
		)
		(pad "258" smd rect
			(at -4.59994 101.149912 270)
			(size 1.8034 0.508)
			(layers "B.Cu" "B.Mask" "B.Paste")
			(net "M_G_DQ<47>")
		)
		(pad "259" smd rect
			(at -4.59994 102.00005 270)
			(size 1.8034 0.508)
			(layers "B.Cu" "B.Mask" "B.Paste")
			(net "GND")
		)
		(pad "260" smd rect
			(at -4.59994 102.849934 270)
			(size 1.8034 0.508)
			(layers "B.Cu" "B.Mask" "B.Paste")
			(net "M_G_DQ<43>")
		)
		(pad "261" smd rect
			(at -4.59994 103.700072 270)
			(size 1.8034 0.508)
			(layers "B.Cu" "B.Mask" "B.Paste")
			(net "GND")
		)
		(pad "262" smd rect
			(at -4.59994 104.549956 270)
			(size 1.8034 0.508)
			(layers "B.Cu" "B.Mask" "B.Paste")
			(net "M_G_DQ<53>")
		)
		(pad "263" smd rect
			(at -4.59994 105.400094 270)
			(size 1.8034 0.508)
			(layers "B.Cu" "B.Mask" "B.Paste")
			(net "GND")
		)
		(pad "264" smd rect
			(at -4.59994 106.249978 270)
			(size 1.8034 0.508)
			(layers "B.Cu" "B.Mask" "B.Paste")
			(net "M_G_DQ<49>")
		)
		(pad "265" smd rect
			(at -4.59994 107.100116 270)
			(size 1.8034 0.508)
			(layers "B.Cu" "B.Mask" "B.Paste")
			(net "GND")
		)
		(pad "266" smd rect
			(at -4.59994 107.95 270)
			(size 1.8034 0.508)
			(layers "B.Cu" "B.Mask" "B.Paste")
			(net "M_G_DQS_DN<6>")
		)
		(pad "267" smd rect
			(at -4.59994 108.799884 270)
			(size 1.8034 0.508)
			(layers "B.Cu" "B.Mask" "B.Paste")
			(net "M_G_DQS_DP<6>")
		)
		(pad "268" smd rect
			(at -4.59994 109.650022 270)
			(size 1.8034 0.508)
			(layers "B.Cu" "B.Mask" "B.Paste")
			(net "GND")
		)
		(pad "269" smd rect
			(at -4.59994 110.499906 270)
			(size 1.8034 0.508)
			(layers "B.Cu" "B.Mask" "B.Paste")
			(net "M_G_DQ<55>")
		)
		(pad "270" smd rect
			(at -4.59994 111.350044 270)
			(size 1.8034 0.508)
			(layers "B.Cu" "B.Mask" "B.Paste")
			(net "GND")
		)
		(pad "271" smd rect
			(at -4.59994 112.199928 270)
			(size 1.8034 0.508)
			(layers "B.Cu" "B.Mask" "B.Paste")
			(net "M_G_DQ<51>")
		)
		(pad "272" smd rect
			(at -4.59994 113.050066 270)
			(size 1.8034 0.508)
			(layers "B.Cu" "B.Mask" "B.Paste")
			(net "GND")
		)
		(pad "273" smd rect
			(at -4.59994 113.89995 270)
			(size 1.8034 0.508)
			(layers "B.Cu" "B.Mask" "B.Paste")
			(net "M_G_DQ<61>")
		)
		(pad "274" smd rect
			(at -4.59994 114.750088 270)
			(size 1.8034 0.508)
			(layers "B.Cu" "B.Mask" "B.Paste")
			(net "GND")
		)
		(pad "275" smd rect
			(at -4.59994 115.599972 270)
			(size 1.8034 0.508)
			(layers "B.Cu" "B.Mask" "B.Paste")
			(net "M_G_DQ<57>")
		)
		(pad "276" smd rect
			(at -4.59994 116.45011 270)
			(size 1.8034 0.508)
			(layers "B.Cu" "B.Mask" "B.Paste")
			(net "GND")
		)
		(pad "277" smd rect
			(at -4.59994 117.299994 270)
			(size 1.8034 0.508)
			(layers "B.Cu" "B.Mask" "B.Paste")
			(net "M_G_DQS_DN<7>")
		)
		(pad "278" smd rect
			(at -4.59994 118.149878 270)
			(size 1.8034 0.508)
			(layers "B.Cu" "B.Mask" "B.Paste")
			(net "M_G_DQS_DP<7>")
		)
		(pad "279" smd rect
			(at -4.59994 119.000016 270)
			(size 1.8034 0.508)
			(layers "B.Cu" "B.Mask" "B.Paste")
			(net "GND")
		)
		(pad "280" smd rect
			(at -4.59994 119.8499 270)
			(size 1.8034 0.508)
			(layers "B.Cu" "B.Mask" "B.Paste")
			(net "M_G_DQ<63>")
		)
		(pad "281" smd rect
			(at -4.59994 120.700038 270)
			(size 1.8034 0.508)
			(layers "B.Cu" "B.Mask" "B.Paste")
			(net "GND")
		)
		(pad "282" smd rect
			(at -4.59994 121.549922 270)
			(size 1.8034 0.508)
			(layers "B.Cu" "B.Mask" "B.Paste")
			(net "M_G_DQ<59>")
		)
		(pad "283" smd rect
			(at -4.59994 122.40006 270)
			(size 1.8034 0.508)
			(layers "B.Cu" "B.Mask" "B.Paste")
			(net "GND")
		)
		(pad "284" smd rect
			(at -4.59994 123.249944 270)
			(size 1.8034 0.508)
			(layers "B.Cu" "B.Mask" "B.Paste")
			(net "PVPP_GHJ")
		)
		(pad "285" smd rect
			(at -4.59994 124.100082 270)
			(size 1.8034 0.508)
			(layers "B.Cu" "B.Mask" "B.Paste")
			(net "SMB_DDR_GHJ_VPP_SDA")
		)
		(pad "286" smd rect
			(at -4.59994 124.949966 270)
			(size 1.8034 0.508)
			(layers "B.Cu" "B.Mask" "B.Paste")
			(net "PVPP_GHJ")
		)
		(pad "287" smd rect
			(at -4.59994 125.800104 270)
			(size 1.8034 0.508)
			(layers "B.Cu" "B.Mask" "B.Paste")
			(net "PVPP_GHJ")
		)
		(pad "288" smd rect
			(at -4.59994 126.649988 270)
			(size 1.8034 0.508)
			(layers "B.Cu" "B.Mask" "B.Paste")
			(net "PVPP_GHJ")
		)
	)
)
